(kicad_pcb
	(version 20260206)
	(generator "pcbnew")
	(generator_version "10.0")
	(general
		(thickness 1.6)
		(legacy_teardrops no)
	)
	(paper "A4")
	(title_block
		(title "04192023_DAF0TMB3IC0_F0TG_MB_C_brd_V02_OCP.brd")
		(comment 1 "Grand Teton / footprints 3805-3812 of 8354")
	)
	(layers
		(0 "F.Cu" signal "TOP")
		(4 "In1.Cu" signal "GND")
		(6 "In2.Cu" signal "IN1")
		(8 "In3.Cu" signal "GND1")
		(10 "In4.Cu" signal "IN2")
		(12 "In5.Cu" signal "GND2")
		(14 "In6.Cu" signal "IN3")
		(16 "In7.Cu" signal "GND3")
		(18 "In8.Cu" signal "VCC")
		(20 "In9.Cu" signal "VCC1")
		(22 "In10.Cu" signal "GND4")
		(24 "In11.Cu" signal "IN4")
		(26 "In12.Cu" signal "GND5")
		(28 "In13.Cu" signal "IN5")
		(30 "In14.Cu" signal "GND6")
		(32 "In15.Cu" signal "IN6")
		(34 "In16.Cu" signal "GND7")
		(2 "B.Cu" signal "BOTTOM")
		(9 "F.Adhes" user "F.Adhesive")
		(11 "B.Adhes" user "B.Adhesive")
		(13 "F.Paste" user "Package Geometry/Pastemask Top")
		(15 "B.Paste" user "Package Geometry/Pastemask Bottom")
		(5 "F.SilkS" user "Ref Des/Silkscreen Top")
		(7 "B.SilkS" user "Ref Des/Silkscreen Bottom")
		(1 "F.Mask" user "Board Geometry/Soldermask Top")
		(3 "B.Mask" user "Board Geometry/Soldermask Bottom")
		(17 "Dwgs.User" user "User.Drawings")
		(19 "Cmts.User" user "User.Comments")
		(21 "Eco1.User" user "User.Eco1")
		(23 "Eco2.User" user "User.Eco2")
		(25 "Edge.Cuts" user "Board Geometry/Outline")
		(27 "Margin" user)
		(31 "F.CrtYd" user "Package Geometry/Place Bound Top")
		(29 "B.CrtYd" user "Package Geometry/Place Bound Bottom")
		(35 "F.Fab" user "Ref Des/Assembly Top")
		(33 "B.Fab" user "Ref Des/Assembly Bottom")
	)
	(footprint ""
		(layer "F.Cu")
		(at 420.153338 -157.606492 -90)
		(property "Reference" "PR445"
			(at 0 0 270)
			(layer "F.SilkS")
			(hide yes)
			(effects
				(font
					(size 1.27 1.27)
				)
			)
		)
		(property "Value" ""
			(at 0 0 270)
			(layer "F.Fab")
			(effects
				(font
					(size 1.27 1.27)
				)
			)
		)
		(duplicate_pad_numbers_are_jumpers no)
		(fp_line
			(start -0.7874 0.4064)
			(end -0.7874 -0.4064)
			(stroke
				(width 0.1524)
				(type default)
			)
			(layer "F.SilkS")
		)
		(fp_line
			(start 0.7874 0.4064)
			(end -0.7874 0.4064)
			(stroke
				(width 0.1524)
				(type default)
			)
			(layer "F.SilkS")
		)
		(fp_line
			(start -0.7874 -0.4064)
			(end 0.7874 -0.4064)
			(stroke
				(width 0.1524)
				(type default)
			)
			(layer "F.SilkS")
		)
		(fp_line
			(start 0.7874 -0.4064)
			(end 0.7874 0.4064)
			(stroke
				(width 0.1524)
				(type default)
			)
			(layer "F.SilkS")
		)
		(fp_line
			(start -0.67945 0.3048)
			(end -0.67945 -0.305054)
			(stroke
				(width 0.1)
				(type default)
			)
			(layer "F.Fab")
		)
		(fp_line
			(start -0.12065 0.3048)
			(end -0.67945 0.3048)
			(stroke
				(width 0.1)
				(type default)
			)
			(layer "F.Fab")
		)
		(fp_line
			(start 0.120396 0.3048)
			(end 0.120396 0.2794)
			(stroke
				(width 0.1)
				(type default)
			)
			(layer "F.Fab")
		)
		(fp_line
			(start 0.67945 0.3048)
			(end 0.120396 0.3048)
			(stroke
				(width 0.1)
				(type default)
			)
			(layer "F.Fab")
		)
		(fp_line
			(start -0.12065 0.2794)
			(end -0.12065 0.3048)
			(stroke
				(width 0.1)
				(type default)
			)
			(layer "F.Fab")
		)
		(fp_line
			(start 0.120396 0.2794)
			(end -0.12065 0.2794)
			(stroke
				(width 0.1)
				(type default)
			)
			(layer "F.Fab")
		)
		(fp_line
			(start -0.12065 -0.2794)
			(end 0.12065 -0.2794)
			(stroke
				(width 0.1)
				(type default)
			)
			(layer "F.Fab")
		)
		(fp_line
			(start 0.12065 -0.2794)
			(end 0.12065 -0.3048)
			(stroke
				(width 0.1)
				(type default)
			)
			(layer "F.Fab")
		)
		(fp_line
			(start 0.12065 -0.3048)
			(end 0.67945 -0.3048)
			(stroke
				(width 0.1)
				(type default)
			)
			(layer "F.Fab")
		)
		(fp_line
			(start 0.67945 -0.3048)
			(end 0.67945 0.3048)
			(stroke
				(width 0.1)
				(type default)
			)
			(layer "F.Fab")
		)
		(fp_line
			(start -0.67945 -0.305054)
			(end -0.12065 -0.305054)
			(stroke
				(width 0.1)
				(type default)
			)
			(layer "F.Fab")
		)
		(fp_line
			(start -0.12065 -0.305054)
			(end -0.12065 -0.2794)
			(stroke
				(width 0.1)
				(type default)
			)
			(layer "F.Fab")
		)
		(pad "1" smd circle
			(at -0.40005 0 270)
			(size 0 0)
			(layers "F.Cu" "F.Mask" "F.Paste")
			(net "PVDDCR_CPU0_P0_PVCC")
		)
		(pad "2" smd circle
			(at 0.40005 0 270)
			(size 0 0)
			(layers "F.Cu" "F.Mask" "F.Paste")
			(net "P5V_AUX")
		)
	)
	(footprint ""
		(layer "F.Cu")
		(at 394.981938 -393.9032 90)
		(property "Reference" "R1097"
			(at 0 0 90)
			(layer "F.SilkS")
			(hide yes)
			(effects
				(font
					(size 1.27 1.27)
				)
			)
		)
		(property "Value" ""
			(at 0 0 90)
			(layer "F.Fab")
			(effects
				(font
					(size 1.27 1.27)
				)
			)
		)
		(duplicate_pad_numbers_are_jumpers no)
		(fp_line
			(start 0.32512 -0.175006)
			(end 0.32512 0.175006)
			(stroke
				(width 0.1)
				(type default)
			)
			(layer "F.Fab")
		)
		(fp_line
			(start -0.32512 -0.175006)
			(end 0.32512 -0.175006)
			(stroke
				(width 0.1)
				(type default)
			)
			(layer "F.Fab")
		)
		(fp_line
			(start 0.32512 0.175006)
			(end -0.32512 0.175006)
			(stroke
				(width 0.1)
				(type default)
			)
			(layer "F.Fab")
		)
		(fp_line
			(start -0.32512 0.175006)
			(end -0.32512 -0.175006)
			(stroke
				(width 0.1)
				(type default)
			)
			(layer "F.Fab")
		)
		(pad "1" smd rect
			(at -0.2667 0 90)
			(size 0.3048 0.381)
			(layers "F.Cu" "F.Mask" "F.Paste")
			(net "P1V8_CPU0_RT_1D")
		)
		(pad "2" smd rect
			(at 0.2667 0 270)
			(size 0.3048 0.381)
			(layers "F.Cu" "F.Mask" "F.Paste")
			(net "RT_CPU0_P3_ADDR3")
		)
	)
	(footprint ""
		(layer "F.Cu")
		(at 245.222268 -44.03979 90)
		(property "Reference" "C1278"
			(at 0 0 90)
			(layer "F.SilkS")
			(hide yes)
			(effects
				(font
					(size 1.27 1.27)
				)
			)
		)
		(property "Value" ""
			(at 0 0 90)
			(layer "F.Fab")
			(effects
				(font
					(size 1.27 1.27)
				)
			)
		)
		(duplicate_pad_numbers_are_jumpers no)
		(fp_line
			(start 0.7874 -0.4064)
			(end 0.7874 0.4064)
			(stroke
				(width 0.1524)
				(type default)
			)
			(layer "F.SilkS")
		)
		(fp_line
			(start -0.7874 -0.4064)
			(end 0.7874 -0.4064)
			(stroke
				(width 0.1524)
				(type default)
			)
			(layer "F.SilkS")
		)
		(fp_line
			(start 0.7874 0.4064)
			(end -0.7874 0.4064)
			(stroke
				(width 0.1524)
				(type default)
			)
			(layer "F.SilkS")
		)
		(fp_line
			(start -0.7874 0.4064)
			(end -0.7874 -0.4064)
			(stroke
				(width 0.1524)
				(type default)
			)
			(layer "F.SilkS")
		)
		(fp_line
			(start -0.12065 -0.305054)
			(end -0.12065 -0.2794)
			(stroke
				(width 0.1)
				(type default)
			)
			(layer "F.Fab")
		)
		(fp_line
			(start -0.67945 -0.305054)
			(end -0.12065 -0.305054)
			(stroke
				(width 0.1)
				(type default)
			)
			(layer "F.Fab")
		)
		(fp_line
			(start 0.67945 -0.3048)
			(end 0.67945 0.3048)
			(stroke
				(width 0.1)
				(type default)
			)
			(layer "F.Fab")
		)
		(fp_line
			(start 0.12065 -0.3048)
			(end 0.67945 -0.3048)
			(stroke
				(width 0.1)
				(type default)
			)
			(layer "F.Fab")
		)
		(fp_line
			(start 0.12065 -0.2794)
			(end 0.12065 -0.3048)
			(stroke
				(width 0.1)
				(type default)
			)
			(layer "F.Fab")
		)
		(fp_line
			(start -0.12065 -0.2794)
			(end 0.12065 -0.2794)
			(stroke
				(width 0.1)
				(type default)
			)
			(layer "F.Fab")
		)
		(fp_line
			(start 0.120396 0.2794)
			(end -0.12065 0.2794)
			(stroke
				(width 0.1)
				(type default)
			)
			(layer "F.Fab")
		)
		(fp_line
			(start -0.12065 0.2794)
			(end -0.12065 0.3048)
			(stroke
				(width 0.1)
				(type default)
			)
			(layer "F.Fab")
		)
		(fp_line
			(start 0.67945 0.3048)
			(end 0.120396 0.3048)
			(stroke
				(width 0.1)
				(type default)
			)
			(layer "F.Fab")
		)
		(fp_line
			(start 0.120396 0.3048)
			(end 0.120396 0.2794)
			(stroke
				(width 0.1)
				(type default)
			)
			(layer "F.Fab")
		)
		(fp_line
			(start -0.12065 0.3048)
			(end -0.67945 0.3048)
			(stroke
				(width 0.1)
				(type default)
			)
			(layer "F.Fab")
		)
		(fp_line
			(start -0.67945 0.3048)
			(end -0.67945 -0.305054)
			(stroke
				(width 0.1)
				(type default)
			)
			(layer "F.Fab")
		)
		(pad "1" smd circle
			(at -0.40005 0 90)
			(size 0 0)
			(layers "F.Cu" "F.Mask" "F.Paste")
			(net "P12V_E1S_0_R")
		)
		(pad "2" smd circle
			(at 0.40005 0 90)
			(size 0 0)
			(layers "F.Cu" "F.Mask" "F.Paste")
			(net "GND")
		)
	)
	(footprint ""
		(layer "F.Cu")
		(at 186.53252 -19.435572 90)
		(property "Reference" "R6064"
			(at 0 0 90)
			(layer "F.SilkS")
			(hide yes)
			(effects
				(font
					(size 1.27 1.27)
				)
			)
		)
		(property "Value" ""
			(at 0 0 90)
			(layer "F.Fab")
			(effects
				(font
					(size 1.27 1.27)
				)
			)
		)
		(duplicate_pad_numbers_are_jumpers no)
		(fp_line
			(start 0.7874 -0.4064)
			(end 0.7874 0.4064)
			(stroke
				(width 0.1524)
				(type default)
			)
			(layer "F.SilkS")
		)
		(fp_line
			(start -0.7874 -0.4064)
			(end 0.7874 -0.4064)
			(stroke
				(width 0.1524)
				(type default)
			)
			(layer "F.SilkS")
		)
		(fp_line
			(start 0.7874 0.4064)
			(end -0.7874 0.4064)
			(stroke
				(width 0.1524)
				(type default)
			)
			(layer "F.SilkS")
		)
		(fp_line
			(start -0.7874 0.4064)
			(end -0.7874 -0.4064)
			(stroke
				(width 0.1524)
				(type default)
			)
			(layer "F.SilkS")
		)
		(fp_line
			(start -0.12065 -0.305054)
			(end -0.12065 -0.2794)
			(stroke
				(width 0.1)
				(type default)
			)
			(layer "F.Fab")
		)
		(fp_line
			(start -0.67945 -0.305054)
			(end -0.12065 -0.305054)
			(stroke
				(width 0.1)
				(type default)
			)
			(layer "F.Fab")
		)
		(fp_line
			(start 0.67945 -0.3048)
			(end 0.67945 0.3048)
			(stroke
				(width 0.1)
				(type default)
			)
			(layer "F.Fab")
		)
		(fp_line
			(start 0.12065 -0.3048)
			(end 0.67945 -0.3048)
			(stroke
				(width 0.1)
				(type default)
			)
			(layer "F.Fab")
		)
		(fp_line
			(start 0.12065 -0.2794)
			(end 0.12065 -0.3048)
			(stroke
				(width 0.1)
				(type default)
			)
			(layer "F.Fab")
		)
		(fp_line
			(start -0.12065 -0.2794)
			(end 0.12065 -0.2794)
			(stroke
				(width 0.1)
				(type default)
			)
			(layer "F.Fab")
		)
		(fp_line
			(start 0.120396 0.2794)
			(end -0.12065 0.2794)
			(stroke
				(width 0.1)
				(type default)
			)
			(layer "F.Fab")
		)
		(fp_line
			(start -0.12065 0.2794)
			(end -0.12065 0.3048)
			(stroke
				(width 0.1)
				(type default)
			)
			(layer "F.Fab")
		)
		(fp_line
			(start 0.67945 0.3048)
			(end 0.120396 0.3048)
			(stroke
				(width 0.1)
				(type default)
			)
			(layer "F.Fab")
		)
		(fp_line
			(start 0.120396 0.3048)
			(end 0.120396 0.2794)
			(stroke
				(width 0.1)
				(type default)
			)
			(layer "F.Fab")
		)
		(fp_line
			(start -0.12065 0.3048)
			(end -0.67945 0.3048)
			(stroke
				(width 0.1)
				(type default)
			)
			(layer "F.Fab")
		)
		(fp_line
			(start -0.67945 0.3048)
			(end -0.67945 -0.305054)
			(stroke
				(width 0.1)
				(type default)
			)
			(layer "F.Fab")
		)
		(pad "1" smd circle
			(at -0.40005 0 90)
			(size 0 0)
			(layers "F.Cu" "F.Mask" "F.Paste")
			(net "UART_CPU0_SCM_LVC3_UART1_RX")
		)
		(pad "2" smd circle
			(at 0.40005 0 90)
			(size 0 0)
			(layers "F.Cu" "F.Mask" "F.Paste")
			(net "UART_CPU0_SCM_LVC3_UART1_R_RX")
		)
	)
	(footprint ""
		(layer "F.Cu")
		(at 101.346 -412.931102 -90)
		(property "Reference" "R4210"
			(at 0 0 270)
			(layer "F.SilkS")
			(hide yes)
			(effects
				(font
					(size 1.27 1.27)
				)
			)
		)
		(property "Value" ""
			(at 0 0 270)
			(layer "F.Fab")
			(effects
				(font
					(size 1.27 1.27)
				)
			)
		)
		(duplicate_pad_numbers_are_jumpers no)
		(fp_line
			(start -0.7874 0.4064)
			(end -0.7874 -0.4064)
			(stroke
				(width 0.1524)
				(type default)
			)
			(layer "F.SilkS")
		)
		(fp_line
			(start 0.7874 0.4064)
			(end -0.7874 0.4064)
			(stroke
				(width 0.1524)
				(type default)
			)
			(layer "F.SilkS")
		)
		(fp_line
			(start -0.7874 -0.4064)
			(end 0.7874 -0.4064)
			(stroke
				(width 0.1524)
				(type default)
			)
			(layer "F.SilkS")
		)
		(fp_line
			(start 0.7874 -0.4064)
			(end 0.7874 0.4064)
			(stroke
				(width 0.1524)
				(type default)
			)
			(layer "F.SilkS")
		)
		(fp_line
			(start -0.67945 0.3048)
			(end -0.67945 -0.305054)
			(stroke
				(width 0.1)
				(type default)
			)
			(layer "F.Fab")
		)
		(fp_line
			(start -0.12065 0.3048)
			(end -0.67945 0.3048)
			(stroke
				(width 0.1)
				(type default)
			)
			(layer "F.Fab")
		)
		(fp_line
			(start 0.120396 0.3048)
			(end 0.120396 0.2794)
			(stroke
				(width 0.1)
				(type default)
			)
			(layer "F.Fab")
		)
		(fp_line
			(start 0.67945 0.3048)
			(end 0.120396 0.3048)
			(stroke
				(width 0.1)
				(type default)
			)
			(layer "F.Fab")
		)
		(fp_line
			(start -0.12065 0.2794)
			(end -0.12065 0.3048)
			(stroke
				(width 0.1)
				(type default)
			)
			(layer "F.Fab")
		)
		(fp_line
			(start 0.120396 0.2794)
			(end -0.12065 0.2794)
			(stroke
				(width 0.1)
				(type default)
			)
			(layer "F.Fab")
		)
		(fp_line
			(start -0.12065 -0.2794)
			(end 0.12065 -0.2794)
			(stroke
				(width 0.1)
				(type default)
			)
			(layer "F.Fab")
		)
		(fp_line
			(start 0.12065 -0.2794)
			(end 0.12065 -0.3048)
			(stroke
				(width 0.1)
				(type default)
			)
			(layer "F.Fab")
		)
		(fp_line
			(start 0.12065 -0.3048)
			(end 0.67945 -0.3048)
			(stroke
				(width 0.1)
				(type default)
			)
			(layer "F.Fab")
		)
		(fp_line
			(start 0.67945 -0.3048)
			(end 0.67945 0.3048)
			(stroke
				(width 0.1)
				(type default)
			)
			(layer "F.Fab")
		)
		(fp_line
			(start -0.67945 -0.305054)
			(end -0.12065 -0.305054)
			(stroke
				(width 0.1)
				(type default)
			)
			(layer "F.Fab")
		)
		(fp_line
			(start -0.12065 -0.305054)
			(end -0.12065 -0.2794)
			(stroke
				(width 0.1)
				(type default)
			)
			(layer "F.Fab")
		)
		(pad "1" smd circle
			(at -0.40005 0 270)
			(size 0 0)
			(layers "F.Cu" "F.Mask" "F.Paste")
			(net "P3V3_AUX")
		)
		(pad "2" smd circle
			(at 0.40005 0 270)
			(size 0 0)
			(layers "F.Cu" "F.Mask" "F.Paste")
			(net "FM_THERMAL_ALERT_N")
		)
	)
	(footprint ""
		(layer "F.Cu")
		(at 94.1832 -401.1676 180)
		(property "Reference" "R1436"
			(at 0 0 180)
			(layer "F.SilkS")
			(hide yes)
			(effects
				(font
					(size 1.27 1.27)
				)
			)
		)
		(property "Value" ""
			(at 0 0 180)
			(layer "F.Fab")
			(effects
				(font
					(size 1.27 1.27)
				)
			)
		)
		(duplicate_pad_numbers_are_jumpers no)
		(fp_line
			(start 0.32512 0.175006)
			(end -0.32512 0.175006)
			(stroke
				(width 0.1)
				(type default)
			)
			(layer "F.Fab")
		)
		(fp_line
			(start 0.32512 -0.175006)
			(end 0.32512 0.175006)
			(stroke
				(width 0.1)
				(type default)
			)
			(layer "F.Fab")
		)
		(fp_line
			(start -0.32512 0.175006)
			(end -0.32512 -0.175006)
			(stroke
				(width 0.1)
				(type default)
			)
			(layer "F.Fab")
		)
		(fp_line
			(start -0.32512 -0.175006)
			(end 0.32512 -0.175006)
			(stroke
				(width 0.1)
				(type default)
			)
			(layer "F.Fab")
		)
		(pad "1" smd rect
			(at -0.2667 0 180)
			(size 0.3048 0.381)
			(layers "F.Cu" "F.Mask" "F.Paste")
			(net "P1V8_CPU1_RT_1D")
		)
		(pad "2" smd rect
			(at 0.2667 0)
			(size 0.3048 0.381)
			(layers "F.Cu" "F.Mask" "F.Paste")
			(net "SMB_RT_CPU1_P0_ROM_MUX_1D_SDA")
		)
	)
	(footprint ""
		(layer "F.Cu")
		(at 63.411354 -373.03583 -90)
		(property "Reference" "C815"
			(at 0 0 270)
			(layer "F.SilkS")
			(hide yes)
			(effects
				(font
					(size 1.27 1.27)
				)
			)
		)
		(property "Value" ""
			(at 0 0 270)
			(layer "F.Fab")
			(effects
				(font
					(size 1.27 1.27)
				)
			)
		)
		(duplicate_pad_numbers_are_jumpers no)
		(fp_line
			(start -0.299974 0.150114)
			(end -0.299974 -0.150114)
			(stroke
				(width 0.1)
				(type default)
			)
			(layer "F.Fab")
		)
		(fp_line
			(start 0.299974 0.150114)
			(end -0.299974 0.150114)
			(stroke
				(width 0.1)
				(type default)
			)
			(layer "F.Fab")
		)
		(fp_line
			(start -0.299974 -0.150114)
			(end 0.299974 -0.150114)
			(stroke
				(width 0.1)
				(type default)
			)
			(layer "F.Fab")
		)
		(fp_line
			(start 0.299974 -0.150114)
			(end 0.299974 0.150114)
			(stroke
				(width 0.1)
				(type default)
			)
			(layer "F.Fab")
		)
		(pad "1" smd rect
			(at -0.2667 0 270)
			(size 0.3048 0.381)
			(layers "F.Cu" "F.Mask" "F.Paste")
			(net "P5E_CPU1_P0_TX_C_DP<11>")
		)
		(pad "2" smd rect
			(at 0.2667 0 270)
			(size 0.3048 0.381)
			(layers "F.Cu" "F.Mask" "F.Paste")
			(net "P5E_CPU1_P0_TX_DP<11>")
		)
	)
	(footprint ""
		(layer "F.Cu")
		(at 365.794798 -427.39691 180)
		(property "Reference" "R686"
			(at 0 0 180)
			(layer "F.SilkS")
			(hide yes)
			(effects
				(font
					(size 1.27 1.27)
				)
			)
		)
		(property "Value" ""
			(at 0 0 180)
			(layer "F.Fab")
			(effects
				(font
					(size 1.27 1.27)
				)
			)
		)
		(duplicate_pad_numbers_are_jumpers no)
		(fp_line
			(start 0.32512 0.175006)
			(end -0.32512 0.175006)
			(stroke
				(width 0.1)
				(type default)
			)
			(layer "F.Fab")
		)
		(fp_line
			(start 0.32512 -0.175006)
			(end 0.32512 0.175006)
			(stroke
				(width 0.1)
				(type default)
			)
			(layer "F.Fab")
		)
		(fp_line
			(start -0.32512 0.175006)
			(end -0.32512 -0.175006)
			(stroke
				(width 0.1)
				(type default)
			)
			(layer "F.Fab")
		)
		(fp_line
			(start -0.32512 -0.175006)
			(end 0.32512 -0.175006)
			(stroke
				(width 0.1)
				(type default)
			)
			(layer "F.Fab")
		)
		(pad "1" smd rect
			(at -0.2667 0 180)
			(size 0.3048 0.381)
			(layers "F.Cu" "F.Mask" "F.Paste")
			(net "SMB_RT_CPU0_P3_ROM_MUX_1D_SDA")
		)
		(pad "2" smd rect
			(at 0.2667 0)
			(size 0.3048 0.381)
			(layers "F.Cu" "F.Mask" "F.Paste")
			(net "SMB_RT_CPU0_P3_ROM_MUX_1D_R_SDA")
		)
	)
)
